# S9S_MB_2U (Grand Teton) — schematic netlist excerpt (pin names and nets, part order shuffled) for the footprints in the layout excerpt that follows; sources: Cadence DE-HDL packaged netlist, KiCad conversion of 03242023_DA0F0TMBIJ0_F0T_Motherboard_J_brd_V01_OCP.brd

C2049  Q_CAP  0.1UF 25V 10% X7R  pkg 0402  page 250 : A = P5V_ADC_TIC ; B = GND
R4550  Q_RES  49.9 1% CHIP  pkg 0402LF  page 145 : A = SWB_HSC_EN_BUF_R ; B = SWB_HSC_EN_BUF

(kicad_pcb
	(version 20260206)
	(generator "pcbnew")
	(generator_version "10.0")
	(general
		(thickness 1.6)
		(legacy_teardrops no)
	)
	(paper "A4")
	(title_block
		(title "03242023_DA0F0TMBIJ0_F0T_Motherboard_J_brd_V01_OCP.brd")
		(comment 1 "Grand Teton / footprints 2575-2576 of 6105")
	)
	(layers
		(0 "F.Cu" signal "TOP")
		(4 "In1.Cu" signal "GND")
		(6 "In2.Cu" signal "IN1")
		(8 "In3.Cu" signal "GND1")
		(10 "In4.Cu" signal "IN2")
		(12 "In5.Cu" signal "GND2")
		(14 "In6.Cu" signal "IN3")
		(16 "In7.Cu" signal "GND3")
		(18 "In8.Cu" signal "VCC")
		(20 "In9.Cu" signal "VCC1")
		(22 "In10.Cu" signal "GND4")
		(24 "In11.Cu" signal "IN4")
		(26 "In12.Cu" signal "GND5")
		(28 "In13.Cu" signal "IN5")
		(30 "In14.Cu" signal "GND6")
		(32 "In15.Cu" signal "IN6")
		(34 "In16.Cu" signal "GND7")
		(2 "B.Cu" signal "BOTTOM")
		(9 "F.Adhes" user "F.Adhesive")
		(11 "B.Adhes" user "B.Adhesive")
		(13 "F.Paste" user "Package Geometry/Pastemask Top")
		(15 "B.Paste" user "Package Geometry/Pastemask Bottom")
		(5 "F.SilkS" user "Ref Des/Silkscreen Top")
		(7 "B.SilkS" user "Ref Des/Silkscreen Bottom")
		(1 "F.Mask" user "Board Geometry/Soldermask Top")
		(3 "B.Mask" user "Board Geometry/Soldermask Bottom")
		(17 "Dwgs.User" user "User.Drawings")
		(19 "Cmts.User" user "User.Comments")
		(21 "Eco1.User" user "User.Eco1")
		(23 "Eco2.User" user "User.Eco2")
		(25 "Edge.Cuts" user "Board Geometry/Outline")
		(27 "Margin" user)
		(31 "F.CrtYd" user "Package Geometry/Place Bound Top")
		(29 "B.CrtYd" user "Package Geometry/Place Bound Bottom")
		(35 "F.Fab" user "Ref Des/Assembly Top")
		(33 "B.Fab" user "Ref Des/Assembly Bottom")
	)
	(footprint ""
		(layer "F.Cu")
		(at 362.13034 -410.700728)
		(property "Reference" "R4550"
			(at 0 0 0)
			(layer "F.SilkS")
			(hide yes)
			(effects
				(font
					(size 1.27 1.27)
				)
			)
		)
		(property "Value" ""
			(at 0 0 0)
			(layer "F.Fab")
			(effects
				(font
					(size 1.27 1.27)
				)
			)
		)
		(duplicate_pad_numbers_are_jumpers no)
		(fp_line
			(start -0.7874 -0.4064)
			(end 0.7874 -0.4064)
			(stroke
				(width 0.1524)
				(type default)
			)
			(layer "F.SilkS")
		)
		(fp_line
			(start -0.7874 0.4064)
			(end -0.7874 -0.4064)
			(stroke
				(width 0.1524)
				(type default)
			)
			(layer "F.SilkS")
		)
		(fp_line
			(start 0.7874 -0.4064)
			(end 0.7874 0.4064)
			(stroke
				(width 0.1524)
				(type default)
			)
			(layer "F.SilkS")
		)
		(fp_line
			(start 0.7874 0.4064)
			(end -0.7874 0.4064)
			(stroke
				(width 0.1524)
				(type default)
			)
			(layer "F.SilkS")
		)
		(fp_line
			(start -0.67945 -0.305054)
			(end -0.12065 -0.305054)
			(stroke
				(width 0.1)
				(type default)
			)
			(layer "F.Fab")
		)
		(fp_line
			(start -0.67945 0.3048)
			(end -0.67945 -0.305054)
			(stroke
				(width 0.1)
				(type default)
			)
			(layer "F.Fab")
		)
		(fp_line
			(start -0.12065 -0.305054)
			(end -0.12065 -0.2794)
			(stroke
				(width 0.1)
				(type default)
			)
			(layer "F.Fab")
		)
		(fp_line
			(start -0.12065 -0.2794)
			(end 0.12065 -0.2794)
			(stroke
				(width 0.1)
				(type default)
			)
			(layer "F.Fab")
		)
		(fp_line
			(start -0.12065 0.2794)
			(end -0.12065 0.3048)
			(stroke
				(width 0.1)
				(type default)
			)
			(layer "F.Fab")
		)
		(fp_line
			(start -0.12065 0.3048)
			(end -0.67945 0.3048)
			(stroke
				(width 0.1)
				(type default)
			)
			(layer "F.Fab")
		)
		(fp_line
			(start 0.120396 0.2794)
			(end -0.12065 0.2794)
			(stroke
				(width 0.1)
				(type default)
			)
			(layer "F.Fab")
		)
		(fp_line
			(start 0.120396 0.3048)
			(end 0.120396 0.2794)
			(stroke
				(width 0.1)
				(type default)
			)
			(layer "F.Fab")
		)
		(fp_line
			(start 0.12065 -0.3048)
			(end 0.67945 -0.3048)
			(stroke
				(width 0.1)
				(type default)
			)
			(layer "F.Fab")
		)
		(fp_line
			(start 0.12065 -0.2794)
			(end 0.12065 -0.3048)
			(stroke
				(width 0.1)
				(type default)
			)
			(layer "F.Fab")
		)
		(fp_line
			(start 0.67945 -0.3048)
			(end 0.67945 0.3048)
			(stroke
				(width 0.1)
				(type default)
			)
			(layer "F.Fab")
		)
		(fp_line
			(start 0.67945 0.3048)
			(end 0.120396 0.3048)
			(stroke
				(width 0.1)
				(type default)
			)
			(layer "F.Fab")
		)
		(pad "1" smd circle
			(at -0.40005 0)
			(size 0 0)
			(layers "F.Cu" "F.Mask" "F.Paste")
			(net "SWB_HSC_EN_BUF_R")
		)
		(pad "2" smd circle
			(at 0.40005 0)
			(size 0 0)
			(layers "F.Cu" "F.Mask" "F.Paste")
			(net "SWB_HSC_EN_BUF")
		)
	)
	(footprint ""
		(layer "F.Cu")
		(at 36.930584 -109.571282)
		(property "Reference" "C2049"
			(at 0 0 0)
			(layer "F.SilkS")
			(hide yes)
			(effects
				(font
					(size 1.27 1.27)
				)
			)
		)
		(property "Value" ""
			(at 0 0 0)
			(layer "F.Fab")
			(effects
				(font
					(size 1.27 1.27)
				)
			)
		)
		(duplicate_pad_numbers_are_jumpers no)
		(fp_line
			(start -0.7874 -0.4064)
			(end 0.7874 -0.4064)
			(stroke
				(width 0.1524)
				(type default)
			)
			(layer "F.SilkS")
		)
		(fp_line
			(start -0.7874 0.4064)
			(end -0.7874 -0.4064)
			(stroke
				(width 0.1524)
				(type default)
			)
			(layer "F.SilkS")
		)
		(fp_line
			(start 0.7874 -0.4064)
			(end 0.7874 0.4064)
			(stroke
				(width 0.1524)
				(type default)
			)
			(layer "F.SilkS")
		)
		(fp_line
			(start 0.7874 0.4064)
			(end -0.7874 0.4064)
			(stroke
				(width 0.1524)
				(type default)
			)
			(layer "F.SilkS")
		)
		(fp_line
			(start -0.67945 -0.305054)
			(end -0.12065 -0.305054)
			(stroke
				(width 0.1)
				(type default)
			)
			(layer "F.Fab")
		)
		(fp_line
			(start -0.67945 0.3048)
			(end -0.67945 -0.305054)
			(stroke
				(width 0.1)
				(type default)
			)
			(layer "F.Fab")
		)
		(fp_line
			(start -0.12065 -0.305054)
			(end -0.12065 -0.2794)
			(stroke
				(width 0.1)
				(type default)
			)
			(layer "F.Fab")
		)
		(fp_line
			(start -0.12065 -0.2794)
			(end 0.12065 -0.2794)
			(stroke
				(width 0.1)
				(type default)
			)
			(layer "F.Fab")
		)
		(fp_line
			(start -0.12065 0.2794)
			(end -0.12065 0.3048)
			(stroke
				(width 0.1)
				(type default)
			)
			(layer "F.Fab")
		)
		(fp_line
			(start -0.12065 0.3048)
			(end -0.67945 0.3048)
			(stroke
				(width 0.1)
				(type default)
			)
			(layer "F.Fab")
		)
		(fp_line
			(start 0.120396 0.2794)
			(end -0.12065 0.2794)
			(stroke
				(width 0.1)
				(type default)
			)
			(layer "F.Fab")
		)
		(fp_line
			(start 0.120396 0.3048)
			(end 0.120396 0.2794)
			(stroke
				(width 0.1)
				(type default)
			)
			(layer "F.Fab")
		)
		(fp_line
			(start 0.12065 -0.3048)
			(end 0.67945 -0.3048)
			(stroke
				(width 0.1)
				(type default)
			)
			(layer "F.Fab")
		)
		(fp_line
			(start 0.12065 -0.2794)
			(end 0.12065 -0.3048)
			(stroke
				(width 0.1)
				(type default)
			)
			(layer "F.Fab")
		)
		(fp_line
			(start 0.67945 -0.3048)
			(end 0.67945 0.3048)
			(stroke
				(width 0.1)
				(type default)
			)
			(layer "F.Fab")
		)
		(fp_line
			(start 0.67945 0.3048)
			(end 0.120396 0.3048)
			(stroke
				(width 0.1)
				(type default)
			)
			(layer "F.Fab")
		)
		(pad "1" smd circle
			(at -0.40005 0)
			(size 0 0)
			(layers "F.Cu" "F.Mask" "F.Paste")
			(net "P5V_ADC_TIC")
		)
		(pad "2" smd circle
			(at 0.40005 0)
			(size 0 0)
			(layers "F.Cu" "F.Mask" "F.Paste")
			(net "GND")
		)
	)
)
